(kicad_pcb
	(version 20260206)
	(generator "pcbnew")
	(generator_version "10.0")
	(general
		(thickness 1.6)
		(legacy_teardrops no)
	)
	(paper "A4")
	(title_block
		(title "panther-plus-userver — 13130-1b_20150205.brd")
		(comment 1 "Honey Badger (Wiwynn) / footprints 190-198 of 1509")
	)
	(layers
		(0 "F.Cu" signal "TOP")
		(4 "In1.Cu" signal "L2")
		(6 "In2.Cu" signal "L3")
		(8 "In3.Cu" signal "L4")
		(10 "In4.Cu" signal "L5")
		(12 "In5.Cu" signal "L6")
		(14 "In6.Cu" signal "L7")
		(16 "In7.Cu" signal "L8")
		(18 "In8.Cu" signal "L9")
		(20 "In9.Cu" signal "L10")
		(22 "In10.Cu" signal "L11")
		(2 "B.Cu" signal "BOTTOM")
		(9 "F.Adhes" user "F.Adhesive")
		(11 "B.Adhes" user "B.Adhesive")
		(13 "F.Paste" user "Package Geometry/Pastemask Top")
		(15 "B.Paste" user "Package Geometry/Pastemask Bottom")
		(5 "F.SilkS" user "Ref Des/Silkscreen Top")
		(7 "B.SilkS" user "Ref Des/Silkscreen Bottom")
		(1 "F.Mask" user "Board Geometry/Soldermask Top")
		(3 "B.Mask" user "Board Geometry/Soldermask Bottom")
		(17 "Dwgs.User" user "User.Drawings")
		(19 "Cmts.User" user "User.Comments")
		(21 "Eco1.User" user "User.Eco1")
		(23 "Eco2.User" user "User.Eco2")
		(25 "Edge.Cuts" user "Board Geometry/Outline")
		(27 "Margin" user)
		(31 "F.CrtYd" user "Package Geometry/Place Bound Top")
		(29 "B.CrtYd" user "Package Geometry/Place Bound Bottom")
		(35 "F.Fab" user "Ref Des/Assembly Top")
		(33 "B.Fab" user "Ref Des/Assembly Bottom")
	)
	(footprint ""
		(layer "F.Cu")
		(at 92.71 -13.208)
		(property "Reference" "R445"
			(at 0 0 0)
			(layer "F.SilkS")
			(hide yes)
			(effects
				(font
					(size 1.27 1.27)
				)
			)
		)
		(property "Value" "4K7R2F-GP"
			(at 1.7907 -1.1176 0)
			(unlocked yes)
			(layer "F.Fab")
			(hide yes)
			(effects
				(font
					(size 1.016 1.016)
					(thickness 0.1524)
				)
			)
		)
		(property "Device Type" "R402H16"
			(at 1.7907 -2.6416 0)
			(unlocked yes)
			(layer "F.Fab")
			(hide yes)
			(effects
				(font
					(size 1.016 1.016)
					(thickness 0.1524)
				)
			)
		)
		(duplicate_pad_numbers_are_jumpers no)
		(fp_rect
			(start -0.381 0.8382)
			(end 0.381 -0.8382)
			(stroke
				(width 0)
				(type default)
			)
			(fill no)
			(layer "F.CrtYd")
		)
		(fp_rect
			(start -0.381 0.8382)
			(end 0.381 -0.8382)
			(stroke
				(width 0)
				(type default)
			)
			(fill no)
			(layer "F.Fab")
		)
		(pad "1" smd custom
			(at 0 -0.4318)
			(size 0.127 0.127)
			(layers "F.Cu" "F.Mask" "F.Paste")
			(net "P3V3_STBY")
			(options
				(clearance outline)
				(anchor circle)
			)
			(primitives
				(gr_poly
					(pts
						(arc
							(start -0.2032 -0.2794)
							(mid -0.239121 -0.264521)
							(end -0.254 -0.2286)
						)
						(arc
							(start -0.254 0.2286)
							(mid -0.239121 0.264521)
							(end -0.2032 0.2794)
						)
						(arc
							(start 0.2032 0.2794)
							(mid 0.239121 0.264521)
							(end 0.254 0.2286)
						)
						(arc
							(start 0.254 -0.2286)
							(mid 0.239121 -0.264521)
							(end 0.2032 -0.2794)
						)
					)
					(width 0)
					(fill yes)
				)
			)
		)
		(pad "2" smd custom
			(at 0 0.4318)
			(size 0.127 0.127)
			(layers "F.Cu" "F.Mask" "F.Paste")
			(net "SLOT_ID1")
			(options
				(clearance outline)
				(anchor circle)
			)
			(primitives
				(gr_poly
					(pts
						(arc
							(start -0.2032 -0.2794)
							(mid -0.239121 -0.264521)
							(end -0.254 -0.2286)
						)
						(arc
							(start -0.254 0.2286)
							(mid -0.239121 0.264521)
							(end -0.2032 0.2794)
						)
						(arc
							(start 0.2032 0.2794)
							(mid 0.239121 0.264521)
							(end 0.254 0.2286)
						)
						(arc
							(start 0.254 -0.2286)
							(mid 0.239121 -0.264521)
							(end 0.2032 -0.2794)
						)
					)
					(width 0)
					(fill yes)
				)
			)
		)
	)
	(footprint ""
		(layer "F.Cu")
		(at 136.779 -21.082)
		(property "Reference" "C18"
			(at 0 0 0)
			(layer "F.SilkS")
			(hide yes)
			(effects
				(font
					(size 1.27 1.27)
				)
			)
		)
		(property "Value" "SCD1U10V2KX-5GP"
			(at 1.1811 -2.7051 0)
			(unlocked yes)
			(layer "F.Fab")
			(hide yes)
			(effects
				(font
					(size 1.016 1.016)
					(thickness 0.1524)
				)
			)
		)
		(property "Device Type" "C402H22"
			(at 1.1811 -4.2291 0)
			(unlocked yes)
			(layer "F.Fab")
			(hide yes)
			(effects
				(font
					(size 1.016 1.016)
					(thickness 0.1524)
				)
			)
		)
		(duplicate_pad_numbers_are_jumpers no)
		(fp_rect
			(start -0.381 0.7366)
			(end 0.381 -0.7366)
			(stroke
				(width 0)
				(type default)
			)
			(fill no)
			(layer "F.CrtYd")
		)
		(fp_rect
			(start -0.381 0.7366)
			(end 0.381 -0.7366)
			(stroke
				(width 0)
				(type default)
			)
			(fill no)
			(layer "F.Fab")
		)
		(pad "1" smd custom
			(at 0 -0.4572)
			(size 0.1143 0.1143)
			(layers "F.Cu" "F.Mask" "F.Paste")
			(net "P1V2_FPGA_D")
			(options
				(clearance outline)
				(anchor circle)
			)
			(primitives
				(gr_poly
					(pts
						(arc
							(start -0.254 -0.1778)
							(mid -0.239121 -0.213721)
							(end -0.2032 -0.2286)
						)
						(arc
							(start 0.2032 -0.2286)
							(mid 0.239121 -0.213721)
							(end 0.254 -0.1778)
						)
						(arc
							(start 0.254 0.1778)
							(mid 0.239121 0.213721)
							(end 0.2032 0.2286)
						)
						(arc
							(start -0.2032 0.2286)
							(mid -0.239121 0.213721)
							(end -0.254 0.1778)
						)
					)
					(width 0)
					(fill yes)
				)
			)
		)
		(pad "2" smd custom
			(at 0 0.4572)
			(size 0.1143 0.1143)
			(layers "F.Cu" "F.Mask" "F.Paste")
			(net "GND")
			(options
				(clearance outline)
				(anchor circle)
			)
			(primitives
				(gr_poly
					(pts
						(arc
							(start -0.254 -0.1778)
							(mid -0.239121 -0.213721)
							(end -0.2032 -0.2286)
						)
						(arc
							(start 0.2032 -0.2286)
							(mid 0.239121 -0.213721)
							(end 0.254 -0.1778)
						)
						(arc
							(start 0.254 0.1778)
							(mid 0.239121 0.213721)
							(end 0.2032 0.2286)
						)
						(arc
							(start -0.2032 0.2286)
							(mid -0.239121 0.213721)
							(end -0.254 0.1778)
						)
					)
					(width 0)
					(fill yes)
				)
			)
		)
	)
	(footprint ""
		(layer "F.Cu")
		(at 163.7792 -48.1076 90)
		(property "Reference" "R206"
			(at 0 0 90)
			(layer "F.SilkS")
			(hide yes)
			(effects
				(font
					(size 1.27 1.27)
				)
			)
		)
		(property "Value" "0R2J-2-GP"
			(at 1.7907 -1.1176 90)
			(unlocked yes)
			(layer "F.Fab")
			(hide yes)
			(effects
				(font
					(size 1.016 1.016)
					(thickness 0.1524)
				)
			)
		)
		(property "Device Type" "R402H16"
			(at 1.7907 -2.6416 90)
			(unlocked yes)
			(layer "F.Fab")
			(hide yes)
			(effects
				(font
					(size 1.016 1.016)
					(thickness 0.1524)
				)
			)
		)
		(duplicate_pad_numbers_are_jumpers no)
		(fp_rect
			(start -0.381 0.8382)
			(end 0.381 -0.8382)
			(stroke
				(width 0)
				(type default)
			)
			(fill no)
			(layer "F.CrtYd")
		)
		(fp_rect
			(start -0.381 0.8382)
			(end 0.381 -0.8382)
			(stroke
				(width 0)
				(type default)
			)
			(fill no)
			(layer "F.Fab")
		)
		(pad "1" smd custom
			(at 0 -0.4318 90)
			(size 0.127 0.127)
			(layers "F.Cu" "F.Mask" "F.Paste")
			(net "JTAG_PLD_TDO")
			(options
				(clearance outline)
				(anchor circle)
			)
			(primitives
				(gr_poly
					(pts
						(arc
							(start -0.2032 -0.2794)
							(mid -0.239121 -0.264521)
							(end -0.254 -0.2286)
						)
						(arc
							(start -0.254 0.2286)
							(mid -0.239121 0.264521)
							(end -0.2032 0.2794)
						)
						(arc
							(start 0.2032 0.2794)
							(mid 0.239121 0.264521)
							(end 0.254 0.2286)
						)
						(arc
							(start 0.254 -0.2286)
							(mid 0.239121 -0.264521)
							(end 0.2032 -0.2794)
						)
					)
					(width 0)
					(fill yes)
				)
			)
		)
		(pad "2" smd custom
			(at 0 0.4318 90)
			(size 0.127 0.127)
			(layers "F.Cu" "F.Mask" "F.Paste")
			(net "JTAG_PLD_TDO_D")
			(options
				(clearance outline)
				(anchor circle)
			)
			(primitives
				(gr_poly
					(pts
						(arc
							(start -0.2032 -0.2794)
							(mid -0.239121 -0.264521)
							(end -0.254 -0.2286)
						)
						(arc
							(start -0.254 0.2286)
							(mid -0.239121 0.264521)
							(end -0.2032 0.2794)
						)
						(arc
							(start 0.2032 0.2794)
							(mid 0.239121 0.264521)
							(end 0.254 0.2286)
						)
						(arc
							(start 0.254 -0.2286)
							(mid 0.239121 -0.264521)
							(end 0.2032 -0.2794)
						)
					)
					(width 0)
					(fill yes)
				)
			)
		)
	)
	(footprint ""
		(layer "F.Cu")
		(at 156.718 -20.193)
		(property "Reference" "TP14"
			(at 0 0 0)
			(layer "F.SilkS")
			(hide yes)
			(effects
				(font
					(size 1.27 1.27)
				)
			)
		)
		(property "Value" "TPAD28-1-GP-U"
			(at 0.0508 -1.9304 0)
			(unlocked yes)
			(layer "F.Fab")
			(hide yes)
			(effects
				(font
					(size 1.016 1.016)
					(thickness 0.1524)
				)
			)
		)
		(property "Device Type" "TPAD28-1-U"
			(at 0.0508 -3.4544 0)
			(unlocked yes)
			(layer "F.Fab")
			(hide yes)
			(effects
				(font
					(size 1.016 1.016)
					(thickness 0.1524)
				)
			)
		)
		(duplicate_pad_numbers_are_jumpers no)
		(fp_poly
			(pts
				(arc
					(start 0.3556 0)
					(mid -0.3556 0)
					(end 0.3556 0)
				)
			)
			(stroke
				(width 0)
				(type default)
			)
			(fill no)
			(layer "F.CrtYd")
		)
		(fp_poly
			(pts
				(arc
					(start 0.9525 0)
					(mid -0.9525 0)
					(end 0.9525 0)
				)
			)
			(stroke
				(width 0)
				(type default)
			)
			(fill no)
			(layer "F.Fab")
		)
		(pad "1" smd circle
			(at 0 0)
			(size 0.7112 0.7112)
			(layers "F.Cu" "F.Mask" "F.Paste")
			(net "TP_FPGA_P110")
		)
	)
	(footprint ""
		(layer "F.Cu")
		(at 183.388 -55.626 180)
		(property "Reference" "R200"
			(at 0 0 180)
			(layer "F.SilkS")
			(hide yes)
			(effects
				(font
					(size 1.27 1.27)
				)
			)
		)
		(property "Value" "0R2J-2-GP"
			(at 0.064008 -3.993896 180)
			(unlocked yes)
			(layer "F.Fab")
			(hide yes)
			(effects
				(font
					(size 1.016 1.016)
					(thickness 0.1524)
				)
			)
		)
		(property "Device Type" "R402H16"
			(at 0.064008 -5.517896 180)
			(unlocked yes)
			(layer "F.Fab")
			(hide yes)
			(effects
				(font
					(size 1.016 1.016)
					(thickness 0.1524)
				)
			)
		)
		(duplicate_pad_numbers_are_jumpers no)
		(fp_rect
			(start -0.381 0.8382)
			(end 0.381 -0.8382)
			(stroke
				(width 0)
				(type default)
			)
			(fill no)
			(layer "F.CrtYd")
		)
		(fp_rect
			(start -0.381 0.8382)
			(end 0.381 -0.8382)
			(stroke
				(width 0)
				(type default)
			)
			(fill no)
			(layer "F.Fab")
		)
		(pad "1" smd custom
			(at 0 -0.4318 180)
			(size 0.127 0.127)
			(layers "F.Cu" "F.Mask" "F.Paste")
			(net "PV_VDDR_VREF_A")
			(options
				(clearance outline)
				(anchor circle)
			)
			(primitives
				(gr_poly
					(pts
						(arc
							(start -0.2032 -0.2794)
							(mid -0.239121 -0.264521)
							(end -0.254 -0.2286)
						)
						(arc
							(start -0.254 0.2286)
							(mid -0.239121 0.264521)
							(end -0.2032 0.2794)
						)
						(arc
							(start 0.2032 0.2794)
							(mid 0.239121 0.264521)
							(end 0.254 0.2286)
						)
						(arc
							(start 0.254 -0.2286)
							(mid 0.239121 -0.264521)
							(end 0.2032 -0.2794)
						)
					)
					(width 0)
					(fill yes)
				)
			)
		)
		(pad "2" smd custom
			(at 0 0.4318 180)
			(size 0.127 0.127)
			(layers "F.Cu" "F.Mask" "F.Paste")
			(net "DDR3_M_A_VREF_DQ1")
			(options
				(clearance outline)
				(anchor circle)
			)
			(primitives
				(gr_poly
					(pts
						(arc
							(start -0.2032 -0.2794)
							(mid -0.239121 -0.264521)
							(end -0.254 -0.2286)
						)
						(arc
							(start -0.254 0.2286)
							(mid -0.239121 0.264521)
							(end -0.2032 0.2794)
						)
						(arc
							(start 0.2032 0.2794)
							(mid 0.239121 0.264521)
							(end 0.254 0.2286)
						)
						(arc
							(start 0.254 -0.2286)
							(mid 0.239121 -0.264521)
							(end 0.2032 -0.2794)
						)
					)
					(width 0)
					(fill yes)
				)
			)
		)
	)
	(footprint ""
		(layer "F.Cu")
		(at 45.974 -68.072 180)
		(property "Reference" "PC29"
			(at 0 0 180)
			(layer "F.SilkS")
			(hide yes)
			(effects
				(font
					(size 1.27 1.27)
				)
			)
		)
		(property "Value" "SC47U6D3V5MX-1-GP"
			(at 0 -4.9022 180)
			(unlocked yes)
			(layer "F.Fab")
			(hide yes)
			(effects
				(font
					(size 1.016 1.016)
					(thickness 0.1524)
				)
			)
		)
		(property "Device Type" "C805H54"
			(at 0 -6.8072 180)
			(unlocked yes)
			(layer "F.Fab")
			(hide yes)
			(effects
				(font
					(size 1.016 1.016)
					(thickness 0.1524)
				)
			)
		)
		(duplicate_pad_numbers_are_jumpers no)
		(fp_line
			(start 0.6096 0)
			(end -0.6096 0)
			(stroke
				(width 0.3048)
				(type default)
			)
			(layer "F.SilkS")
		)
		(fp_poly
			(pts
				(xy -0.9017 1.4351) (xy 0.9017 1.4351) (xy 0.9017 -1.4351) (xy -0.9017 -1.4351)
			)
			(stroke
				(width 0)
				(type default)
			)
			(fill no)
			(layer "F.CrtYd")
		)
		(fp_poly
			(pts
				(xy 0.9017 1.4351) (xy 0.9017 -1.4351) (xy -0.9017 -1.4351) (xy -0.9017 1.4351)
			)
			(stroke
				(width 0)
				(type default)
			)
			(fill no)
			(layer "F.Fab")
		)
		(pad "1" smd rect
			(at 0 -0.8382 180)
			(size 1.5494 0.9398)
			(layers "F.Cu" "F.Mask" "F.Paste")
			(net "PVNN")
		)
		(pad "2" smd rect
			(at 0 0.8382 180)
			(size 1.5494 0.9398)
			(layers "F.Cu" "F.Mask" "F.Paste")
			(net "GND")
		)
	)
	(footprint ""
		(layer "F.Cu")
		(at 183.642 -37.338 90)
		(property "Reference" "R96"
			(at 0 0 90)
			(layer "F.SilkS")
			(hide yes)
			(effects
				(font
					(size 1.27 1.27)
				)
			)
		)
		(property "Value" "150R2J-L1-GP-U"
			(at 1.7907 -1.1176 90)
			(unlocked yes)
			(layer "F.Fab")
			(hide yes)
			(effects
				(font
					(size 1.016 1.016)
					(thickness 0.1524)
				)
			)
		)
		(property "Device Type" "R402H16"
			(at 1.7907 -2.6416 90)
			(unlocked yes)
			(layer "F.Fab")
			(hide yes)
			(effects
				(font
					(size 1.016 1.016)
					(thickness 0.1524)
				)
			)
		)
		(duplicate_pad_numbers_are_jumpers no)
		(fp_rect
			(start -0.381 0.8382)
			(end 0.381 -0.8382)
			(stroke
				(width 0)
				(type default)
			)
			(fill no)
			(layer "F.CrtYd")
		)
		(fp_rect
			(start -0.381 0.8382)
			(end 0.381 -0.8382)
			(stroke
				(width 0)
				(type default)
			)
			(fill no)
			(layer "F.Fab")
		)
		(pad "1" smd custom
			(at 0 -0.4318 90)
			(size 0.127 0.127)
			(layers "F.Cu" "F.Mask" "F.Paste")
			(net "SVID_CPU_CLK")
			(options
				(clearance outline)
				(anchor circle)
			)
			(primitives
				(gr_poly
					(pts
						(arc
							(start -0.2032 -0.2794)
							(mid -0.239121 -0.264521)
							(end -0.254 -0.2286)
						)
						(arc
							(start -0.254 0.2286)
							(mid -0.239121 0.264521)
							(end -0.2032 0.2794)
						)
						(arc
							(start 0.2032 0.2794)
							(mid 0.239121 0.264521)
							(end 0.254 0.2286)
						)
						(arc
							(start 0.254 -0.2286)
							(mid 0.239121 -0.264521)
							(end 0.2032 -0.2794)
						)
					)
					(width 0)
					(fill yes)
				)
			)
		)
		(pad "2" smd custom
			(at 0 0.4318 90)
			(size 0.127 0.127)
			(layers "F.Cu" "F.Mask" "F.Paste")
			(net "SVID_CLK_A")
			(options
				(clearance outline)
				(anchor circle)
			)
			(primitives
				(gr_poly
					(pts
						(arc
							(start -0.2032 -0.2794)
							(mid -0.239121 -0.264521)
							(end -0.254 -0.2286)
						)
						(arc
							(start -0.254 0.2286)
							(mid -0.239121 0.264521)
							(end -0.2032 0.2794)
						)
						(arc
							(start 0.2032 0.2794)
							(mid 0.239121 0.264521)
							(end 0.254 0.2286)
						)
						(arc
							(start 0.254 -0.2286)
							(mid 0.239121 -0.264521)
							(end 0.2032 -0.2794)
						)
					)
					(width 0)
					(fill yes)
				)
			)
		)
	)
	(footprint ""
		(layer "F.Cu")
		(at 182.5498 -31.7246 180)
		(property "Reference" "PR149"
			(at 0 0 180)
			(layer "F.SilkS")
			(hide yes)
			(effects
				(font
					(size 1.27 1.27)
				)
			)
		)
		(property "Value" "1KR2F-3-GP"
			(at 1.7907 -1.1176 180)
			(unlocked yes)
			(layer "F.Fab")
			(hide yes)
			(effects
				(font
					(size 1.016 1.016)
					(thickness 0.1524)
				)
			)
		)
		(property "Device Type" "R402H16"
			(at 1.7907 -2.6416 180)
			(unlocked yes)
			(layer "F.Fab")
			(hide yes)
			(effects
				(font
					(size 1.016 1.016)
					(thickness 0.1524)
				)
			)
		)
		(duplicate_pad_numbers_are_jumpers no)
		(fp_rect
			(start -0.381 0.8382)
			(end 0.381 -0.8382)
			(stroke
				(width 0)
				(type default)
			)
			(fill no)
			(layer "F.CrtYd")
		)
		(fp_rect
			(start -0.381 0.8382)
			(end 0.381 -0.8382)
			(stroke
				(width 0)
				(type default)
			)
			(fill no)
			(layer "F.Fab")
		)
		(pad "1" smd custom
			(at 0 -0.4318 180)
			(size 0.127 0.127)
			(layers "F.Cu" "F.Mask" "F.Paste")
			(net "VR_PVDDR_A_COMP")
			(options
				(clearance outline)
				(anchor circle)
			)
			(primitives
				(gr_poly
					(pts
						(arc
							(start -0.2032 -0.2794)
							(mid -0.239121 -0.264521)
							(end -0.254 -0.2286)
						)
						(arc
							(start -0.254 0.2286)
							(mid -0.239121 0.264521)
							(end -0.2032 0.2794)
						)
						(arc
							(start 0.2032 0.2794)
							(mid 0.239121 0.264521)
							(end 0.254 0.2286)
						)
						(arc
							(start 0.254 -0.2286)
							(mid 0.239121 -0.264521)
							(end 0.2032 -0.2794)
						)
					)
					(width 0)
					(fill yes)
				)
			)
		)
		(pad "2" smd custom
			(at 0 0.4318 180)
			(size 0.127 0.127)
			(layers "F.Cu" "F.Mask" "F.Paste")
			(net "GND")
			(options
				(clearance outline)
				(anchor circle)
			)
			(primitives
				(gr_poly
					(pts
						(arc
							(start -0.2032 -0.2794)
							(mid -0.239121 -0.264521)
							(end -0.254 -0.2286)
						)
						(arc
							(start -0.254 0.2286)
							(mid -0.239121 0.264521)
							(end -0.2032 0.2794)
						)
						(arc
							(start 0.2032 0.2794)
							(mid 0.239121 0.264521)
							(end 0.254 0.2286)
						)
						(arc
							(start 0.254 -0.2286)
							(mid 0.239121 -0.264521)
							(end 0.2032 -0.2794)
						)
					)
					(width 0)
					(fill yes)
				)
			)
		)
	)
	(footprint ""
		(layer "F.Cu")
		(at 31.0896 -57.9374 -90)
		(property "Reference" "PC12"
			(at 0 0 270)
			(layer "F.SilkS")
			(hide yes)
			(effects
				(font
					(size 1.27 1.27)
				)
			)
		)
		(property "Value" "SC47U16V0MX-GP"
			(at -2.3368 -3.5052 270)
			(unlocked yes)
			(layer "F.Fab")
			(hide yes)
			(effects
				(font
					(size 1.016 1.016)
					(thickness 0.1524)
				)
			)
		)
		(property "Device Type" "C1210H107"
			(at -2.3368 -5.0292 270)
			(unlocked yes)
			(layer "F.Fab")
			(hide yes)
			(effects
				(font
					(size 1.016 1.016)
					(thickness 0.1524)
				)
			)
		)
		(duplicate_pad_numbers_are_jumpers no)
		(fp_rect
			(start -1.4986 1.9685)
			(end 1.4986 -1.9685)
			(stroke
				(width 0)
				(type default)
			)
			(fill no)
			(layer "F.CrtYd")
		)
		(fp_rect
			(start -1.4986 1.9685)
			(end 1.4986 -1.9685)
			(stroke
				(width 0)
				(type default)
			)
			(fill no)
			(layer "F.Fab")
		)
		(pad "1" smd rect
			(at 0 -1.2446 270)
			(size 2.7432 1.1938)
			(layers "F.Cu" "F.Mask" "F.Paste")
			(net "VR_FET_SW_P12V_PVCCP_PVNN")
		)
		(pad "2" smd rect
			(at 0 1.2446 270)
			(size 2.7432 1.1938)
			(layers "F.Cu" "F.Mask" "F.Paste")
			(net "GND")
		)
	)
)
